G04*
G04 #@! TF.GenerationSoftware,Altium Limited,Altium Designer,23.0.1 (38)*
G04*
G04 Layer_Color=2752767*
%FSLAX44Y44*%
%MOMM*%
G71*
G04*
G04 #@! TF.SameCoordinates,9A23C038-B079-480F-8166-AFFB5740F5AE*
G04*
G04*
G04 #@! TF.FilePolarity,Positive*
G04*
G01*
G75*
%ADD49C,0.0508*%
%ADD50C,0.0677*%
D49*
X523000Y206007D02*
X524016Y207023D01*
X525032D01*
X524016Y208039D01*
X525032Y209055D01*
X524016D01*
X523000Y210071D01*
X521984Y209055D01*
X520968D01*
X521984Y208039D01*
X520968Y207023D01*
X521984D01*
X523000Y206007D01*
X522965Y239968D02*
X523981Y240984D01*
X524997D01*
X523981Y242000D01*
X524997Y243016D01*
X523981D01*
X522965Y244032D01*
X521949Y243016D01*
X520933D01*
X521949Y242000D01*
X520933Y240984D01*
X521949D01*
X522965Y239968D01*
X536000Y230659D02*
X537016Y231675D01*
X538032D01*
X537016Y232691D01*
X538032Y233707D01*
X537016D01*
X536000Y234723D01*
X534984Y233707D01*
X533968D01*
X534984Y232691D01*
X533968Y231675D01*
X534984D01*
X536000Y230659D01*
X241871Y252773D02*
X239839Y256837D01*
X243903D01*
X241871Y252773D01*
X231291D02*
X229259Y256837D01*
X233323D01*
X231291Y252773D01*
X220711D02*
X218679Y256837D01*
X222743D01*
X220711Y252773D01*
X210131D02*
X208099Y256837D01*
X212163D01*
X210131Y252773D01*
X199634Y251449D02*
X197602Y255513D01*
X201666D01*
X199634Y251449D01*
X190160Y246739D02*
X188128Y250803D01*
X192192D01*
X190160Y246739D01*
X182390Y239559D02*
X180357Y243623D01*
X184422D01*
X182390Y239559D01*
X174908Y232078D02*
X172876Y236142D01*
X176940D01*
X174908Y232078D01*
X167427Y224597D02*
X165395Y228661D01*
X169459D01*
X167427Y224597D01*
X159946Y217115D02*
X157914Y221179D01*
X161978D01*
X159946Y217115D01*
X152465Y209634D02*
X150433Y213698D01*
X154497D01*
X152465Y209634D01*
X144033Y203244D02*
X142001Y207308D01*
X146065D01*
X144033Y203244D01*
X133555Y201773D02*
X131524Y205837D01*
X135588D01*
X133555Y201773D01*
X122976D02*
X120943Y205837D01*
X125007D01*
X122976Y201773D01*
X112410Y202322D02*
X110378Y206386D01*
X114442D01*
X112410Y202322D01*
X101844Y201773D02*
X99812Y205837D01*
X103876D01*
X101844Y201773D01*
X91264D02*
X89232Y205837D01*
X93296D01*
X91264Y201773D01*
X80684D02*
X78652Y205837D01*
X82716D01*
X80684Y201773D01*
X70105Y201895D02*
X68073Y205959D01*
X72137D01*
X70105Y201895D01*
X62147Y208867D02*
X60115Y212931D01*
X64179D01*
X62147Y208867D01*
X51602Y208001D02*
X49570Y212065D01*
X53634D01*
X51602Y208001D01*
X44897Y199817D02*
X42865Y203881D01*
X46929D01*
X44897Y199817D01*
X46109Y189307D02*
X44077Y193371D01*
X48141D01*
X46109Y189307D01*
X54498Y182860D02*
X52466Y186924D01*
X56530D01*
X54498Y182860D01*
X64966Y184392D02*
X62934Y188456D01*
X66998D01*
X64966Y184392D01*
X73834Y190163D02*
X71802Y194227D01*
X75866D01*
X73834Y190163D01*
X84414D02*
X82382Y194227D01*
X86446D01*
X84414Y190163D01*
X94994D02*
X92962Y194227D01*
X97026D01*
X94994Y190163D01*
X116052D02*
X114020Y194227D01*
X118084D01*
X116052Y190163D01*
X126632D02*
X124600Y194227D01*
X128664D01*
X126632Y190163D01*
X137212Y190197D02*
X135180Y194261D01*
X139244D01*
X137212Y190197D01*
X147587Y192269D02*
X145555Y196332D01*
X149619D01*
X147587Y192269D01*
X156682Y197674D02*
X154650Y201738D01*
X158714D01*
X156682Y197674D01*
X164283Y205033D02*
X162251Y209097D01*
X166315D01*
X164283Y205033D01*
X171765Y212514D02*
X169732Y216578D01*
X173797D01*
X171765Y212514D01*
X179246Y219995D02*
X177214Y224059D01*
X181278D01*
X179246Y219995D01*
X186727Y227476D02*
X184695Y231540D01*
X188759D01*
X186727Y227476D01*
X194208Y234958D02*
X192176Y239021D01*
X196240D01*
X194208Y234958D01*
X203283Y240397D02*
X201251Y244461D01*
X205315D01*
X203283Y240397D01*
X213835Y241163D02*
X211803Y245227D01*
X215867D01*
X213835Y241163D01*
X224415D02*
X222383Y245227D01*
X226447D01*
X224415Y241163D01*
X234995D02*
X232963Y245227D01*
X237027D01*
X234995Y241163D01*
X255209Y243753D02*
X253177Y247817D01*
X257241D01*
X255209Y243753D01*
X252362Y253942D02*
X250330Y258006D01*
X254394D01*
X252362Y253942D01*
X536000Y205968D02*
X537016Y206984D01*
X538032D01*
X537016Y208000D01*
X538032Y209016D01*
X537016D01*
X536000Y210032D01*
X534984Y209016D01*
X533968D01*
X534984Y208000D01*
X533968Y206984D01*
X534984D01*
X536000Y205968D01*
X561000Y100968D02*
X562016Y101984D01*
X563032D01*
X562016Y103000D01*
X563032Y104016D01*
X562016D01*
X561000Y105032D01*
X559984Y104016D01*
X558968D01*
X559984Y103000D01*
X558968Y101984D01*
X559984D01*
X561000Y100968D01*
Y120968D02*
X562016Y121984D01*
X563032D01*
X562016Y123000D01*
X563032Y124016D01*
X562016D01*
X561000Y125032D01*
X559984Y124016D01*
X558968D01*
X559984Y123000D01*
X558968Y121984D01*
X559984D01*
X561000Y120968D01*
X560000Y140968D02*
X561016Y141984D01*
X562032D01*
X561016Y143000D01*
X562032Y144016D01*
X561016D01*
X560000Y145032D01*
X558984Y144016D01*
X557968D01*
X558984Y143000D01*
X557968Y141984D01*
X558984D01*
X560000Y140968D01*
D50*
X177672Y128600D02*
G03*
X177672Y128600I-2032J0D01*
G01*
X126872Y154000D02*
G03*
X126872Y154000I-2032J0D01*
G01*
X152272Y103200D02*
G03*
X152272Y103200I-2032J0D01*
G01*
X406061Y103411D02*
G03*
X406061Y103411I-2032J0D01*
G01*
X457072Y128600D02*
G03*
X457072Y128600I-2032J0D01*
G01*
X431672D02*
G03*
X431672Y128600I-2032J0D01*
G01*
X406272D02*
G03*
X406272Y128600I-2032J0D01*
G01*
X304672Y230200D02*
G03*
X304672Y230200I-2032J0D01*
G01*
X634872Y255600D02*
G03*
X634872Y255600I-2032J0D01*
G01*
Y230200D02*
G03*
X634872Y230200I-2032J0D01*
G01*
Y204800D02*
G03*
X634872Y204800I-2032J0D01*
G01*
Y154000D02*
G03*
X634872Y154000I-2032J0D01*
G01*
Y52400D02*
G03*
X634872Y52400I-2032J0D01*
G01*
X609472Y281000D02*
G03*
X609472Y281000I-2032J0D01*
G01*
Y255600D02*
G03*
X609472Y255600I-2032J0D01*
G01*
Y230200D02*
G03*
X609472Y230200I-2032J0D01*
G01*
Y179400D02*
G03*
X609472Y179400I-2032J0D01*
G01*
Y52400D02*
G03*
X609472Y52400I-2032J0D01*
G01*
Y27000D02*
G03*
X609472Y27000I-2032J0D01*
G01*
X584072Y281000D02*
G03*
X584072Y281000I-2032J0D01*
G01*
Y255600D02*
G03*
X584072Y255600I-2032J0D01*
G01*
Y154000D02*
G03*
X584072Y154000I-2032J0D01*
G01*
Y52400D02*
G03*
X584072Y52400I-2032J0D01*
G01*
X558672Y281000D02*
G03*
X558672Y281000I-2032J0D01*
G01*
Y255600D02*
G03*
X558672Y255600I-2032J0D01*
G01*
Y204800D02*
G03*
X558672Y204800I-2032J0D01*
G01*
Y179400D02*
G03*
X558672Y179400I-2032J0D01*
G01*
Y154000D02*
G03*
X558672Y154000I-2032J0D01*
G01*
Y52400D02*
G03*
X558672Y52400I-2032J0D01*
G01*
X533272Y281000D02*
G03*
X533272Y281000I-2032J0D01*
G01*
Y255600D02*
G03*
X533272Y255600I-2032J0D01*
G01*
Y52400D02*
G03*
X533272Y52400I-2032J0D01*
G01*
X507872Y281000D02*
G03*
X507872Y281000I-2032J0D01*
G01*
Y204800D02*
G03*
X507872Y204800I-2032J0D01*
G01*
Y179400D02*
G03*
X507872Y179400I-2032J0D01*
G01*
Y154000D02*
G03*
X507872Y154000I-2032J0D01*
G01*
Y128600D02*
G03*
X507872Y128600I-2032J0D01*
G01*
Y52400D02*
G03*
X507872Y52400I-2032J0D01*
G01*
X482472Y281000D02*
G03*
X482472Y281000I-2032J0D01*
G01*
Y255600D02*
G03*
X482472Y255600I-2032J0D01*
G01*
Y204800D02*
G03*
X482472Y204800I-2032J0D01*
G01*
Y179400D02*
G03*
X482472Y179400I-2032J0D01*
G01*
Y154000D02*
G03*
X482472Y154000I-2032J0D01*
G01*
Y128600D02*
G03*
X482472Y128600I-2032J0D01*
G01*
Y103200D02*
G03*
X482472Y103200I-2032J0D01*
G01*
Y52400D02*
G03*
X482472Y52400I-2032J0D01*
G01*
X457072Y281000D02*
G03*
X457072Y281000I-2032J0D01*
G01*
Y255600D02*
G03*
X457072Y255600I-2032J0D01*
G01*
Y179400D02*
G03*
X457072Y179400I-2032J0D01*
G01*
Y154000D02*
G03*
X457072Y154000I-2032J0D01*
G01*
Y52400D02*
G03*
X457072Y52400I-2032J0D01*
G01*
X431672Y281000D02*
G03*
X431672Y281000I-2032J0D01*
G01*
Y255600D02*
G03*
X431672Y255600I-2032J0D01*
G01*
Y230200D02*
G03*
X431672Y230200I-2032J0D01*
G01*
Y154000D02*
G03*
X431672Y154000I-2032J0D01*
G01*
Y103200D02*
G03*
X431672Y103200I-2032J0D01*
G01*
Y77800D02*
G03*
X431672Y77800I-2032J0D01*
G01*
Y52400D02*
G03*
X431672Y52400I-2032J0D01*
G01*
X406272Y281000D02*
G03*
X406272Y281000I-2032J0D01*
G01*
Y255600D02*
G03*
X406272Y255600I-2032J0D01*
G01*
Y230200D02*
G03*
X406272Y230200I-2032J0D01*
G01*
Y204800D02*
G03*
X406272Y204800I-2032J0D01*
G01*
Y77800D02*
G03*
X406272Y77800I-2032J0D01*
G01*
Y52400D02*
G03*
X406272Y52400I-2032J0D01*
G01*
X380872Y281000D02*
G03*
X380872Y281000I-2032J0D01*
G01*
Y179400D02*
G03*
X380872Y179400I-2032J0D01*
G01*
Y52400D02*
G03*
X380872Y52400I-2032J0D01*
G01*
X355472Y281000D02*
G03*
X355472Y281000I-2032J0D01*
G01*
Y255600D02*
G03*
X355472Y255600I-2032J0D01*
G01*
Y179400D02*
G03*
X355472Y179400I-2032J0D01*
G01*
Y154000D02*
G03*
X355472Y154000I-2032J0D01*
G01*
Y52400D02*
G03*
X355472Y52400I-2032J0D01*
G01*
X330072Y281000D02*
G03*
X330072Y281000I-2032J0D01*
G01*
Y179400D02*
G03*
X330072Y179400I-2032J0D01*
G01*
Y154000D02*
G03*
X330072Y154000I-2032J0D01*
G01*
Y128600D02*
G03*
X330072Y128600I-2032J0D01*
G01*
Y52400D02*
G03*
X330072Y52400I-2032J0D01*
G01*
X304672Y281000D02*
G03*
X304672Y281000I-2032J0D01*
G01*
Y179400D02*
G03*
X304672Y179400I-2032J0D01*
G01*
Y154000D02*
G03*
X304672Y154000I-2032J0D01*
G01*
Y128600D02*
G03*
X304672Y128600I-2032J0D01*
G01*
Y52400D02*
G03*
X304672Y52400I-2032J0D01*
G01*
X279272Y281000D02*
G03*
X279272Y281000I-2032J0D01*
G01*
Y179400D02*
G03*
X279272Y179400I-2032J0D01*
G01*
Y154000D02*
G03*
X279272Y154000I-2032J0D01*
G01*
Y128600D02*
G03*
X279272Y128600I-2032J0D01*
G01*
Y77800D02*
G03*
X279272Y77800I-2032J0D01*
G01*
Y52400D02*
G03*
X279272Y52400I-2032J0D01*
G01*
X253872Y281000D02*
G03*
X253872Y281000I-2032J0D01*
G01*
Y179400D02*
G03*
X253872Y179400I-2032J0D01*
G01*
Y154000D02*
G03*
X253872Y154000I-2032J0D01*
G01*
Y128600D02*
G03*
X253872Y128600I-2032J0D01*
G01*
Y52400D02*
G03*
X253872Y52400I-2032J0D01*
G01*
X228472Y281000D02*
G03*
X228472Y281000I-2032J0D01*
G01*
Y230200D02*
G03*
X228472Y230200I-2032J0D01*
G01*
Y204800D02*
G03*
X228472Y204800I-2032J0D01*
G01*
Y179400D02*
G03*
X228472Y179400I-2032J0D01*
G01*
Y154000D02*
G03*
X228472Y154000I-2032J0D01*
G01*
Y128600D02*
G03*
X228472Y128600I-2032J0D01*
G01*
Y103200D02*
G03*
X228472Y103200I-2032J0D01*
G01*
Y27000D02*
G03*
X228472Y27000I-2032J0D01*
G01*
X203072Y281000D02*
G03*
X203072Y281000I-2032J0D01*
G01*
Y230200D02*
G03*
X203072Y230200I-2032J0D01*
G01*
Y204800D02*
G03*
X203072Y204800I-2032J0D01*
G01*
Y179400D02*
G03*
X203072Y179400I-2032J0D01*
G01*
Y154000D02*
G03*
X203072Y154000I-2032J0D01*
G01*
Y128600D02*
G03*
X203072Y128600I-2032J0D01*
G01*
Y103200D02*
G03*
X203072Y103200I-2032J0D01*
G01*
Y52400D02*
G03*
X203072Y52400I-2032J0D01*
G01*
Y27000D02*
G03*
X203072Y27000I-2032J0D01*
G01*
X177672Y281000D02*
G03*
X177672Y281000I-2032J0D01*
G01*
Y255600D02*
G03*
X177672Y255600I-2032J0D01*
G01*
Y204800D02*
G03*
X177672Y204800I-2032J0D01*
G01*
Y179400D02*
G03*
X177672Y179400I-2032J0D01*
G01*
Y154000D02*
G03*
X177672Y154000I-2032J0D01*
G01*
Y77800D02*
G03*
X177672Y77800I-2032J0D01*
G01*
Y52400D02*
G03*
X177672Y52400I-2032J0D01*
G01*
Y27000D02*
G03*
X177672Y27000I-2032J0D01*
G01*
X152272Y281000D02*
G03*
X152272Y281000I-2032J0D01*
G01*
Y255600D02*
G03*
X152272Y255600I-2032J0D01*
G01*
Y230200D02*
G03*
X152272Y230200I-2032J0D01*
G01*
Y179400D02*
G03*
X152272Y179400I-2032J0D01*
G01*
Y154000D02*
G03*
X152272Y154000I-2032J0D01*
G01*
Y77800D02*
G03*
X152272Y77800I-2032J0D01*
G01*
Y52400D02*
G03*
X152272Y52400I-2032J0D01*
G01*
Y27000D02*
G03*
X152272Y27000I-2032J0D01*
G01*
X126872Y281000D02*
G03*
X126872Y281000I-2032J0D01*
G01*
Y255600D02*
G03*
X126872Y255600I-2032J0D01*
G01*
Y230200D02*
G03*
X126872Y230200I-2032J0D01*
G01*
Y77800D02*
G03*
X126872Y77800I-2032J0D01*
G01*
Y52400D02*
G03*
X126872Y52400I-2032J0D01*
G01*
Y27000D02*
G03*
X126872Y27000I-2032J0D01*
G01*
X101472Y281000D02*
G03*
X101472Y281000I-2032J0D01*
G01*
Y255600D02*
G03*
X101472Y255600I-2032J0D01*
G01*
Y154000D02*
G03*
X101472Y154000I-2032J0D01*
G01*
Y77800D02*
G03*
X101472Y77800I-2032J0D01*
G01*
Y52400D02*
G03*
X101472Y52400I-2032J0D01*
G01*
Y27000D02*
G03*
X101472Y27000I-2032J0D01*
G01*
X76072Y281000D02*
G03*
X76072Y281000I-2032J0D01*
G01*
Y255600D02*
G03*
X76072Y255600I-2032J0D01*
G01*
Y230200D02*
G03*
X76072Y230200I-2032J0D01*
G01*
Y179400D02*
G03*
X76072Y179400I-2032J0D01*
G01*
Y154000D02*
G03*
X76072Y154000I-2032J0D01*
G01*
Y128600D02*
G03*
X76072Y128600I-2032J0D01*
G01*
Y103200D02*
G03*
X76072Y103200I-2032J0D01*
G01*
Y77800D02*
G03*
X76072Y77800I-2032J0D01*
G01*
Y52400D02*
G03*
X76072Y52400I-2032J0D01*
G01*
Y27000D02*
G03*
X76072Y27000I-2032J0D01*
G01*
X50672Y255600D02*
G03*
X50672Y255600I-2032J0D01*
G01*
Y154000D02*
G03*
X50672Y154000I-2032J0D01*
G01*
Y128600D02*
G03*
X50672Y128600I-2032J0D01*
G01*
Y103200D02*
G03*
X50672Y103200I-2032J0D01*
G01*
Y77800D02*
G03*
X50672Y77800I-2032J0D01*
G01*
Y52400D02*
G03*
X50672Y52400I-2032J0D01*
G01*
X25272Y255600D02*
G03*
X25272Y255600I-2032J0D01*
G01*
Y154000D02*
G03*
X25272Y154000I-2032J0D01*
G01*
Y128600D02*
G03*
X25272Y128600I-2032J0D01*
G01*
Y103200D02*
G03*
X25272Y103200I-2032J0D01*
G01*
Y77800D02*
G03*
X25272Y77800I-2032J0D01*
G01*
Y52400D02*
G03*
X25272Y52400I-2032J0D01*
G01*
M02*
